(kicad_pcb
	(version 20260206)
	(generator "pcbnew")
	(generator_version "10.0")
	(general
		(thickness 1.6)
		(legacy_teardrops no)
	)
	(paper "A4")
	(title_block
		(title "01162023_DA0F0TEBIF0_F0T_Expander_BD_F_brd_V02_OCP.brd")
		(comment 1 "Grand Teton / footprints 7838-7843 of 9728")
	)
	(layers
		(0 "F.Cu" signal "TOP")
		(4 "In1.Cu" signal "GND")
		(6 "In2.Cu" signal "VCC")
		(8 "In3.Cu" signal "VCC1")
		(10 "In4.Cu" signal "GND1")
		(12 "In5.Cu" signal "IN1")
		(14 "In6.Cu" signal "GND2")
		(16 "In7.Cu" signal "IN2")
		(18 "In8.Cu" signal "GND3")
		(20 "In9.Cu" signal "IN3")
		(22 "In10.Cu" signal "GND4")
		(24 "In11.Cu" signal "IN4")
		(26 "In12.Cu" signal "GND5")
		(28 "In13.Cu" signal "IN5")
		(30 "In14.Cu" signal "GND6")
		(32 "In15.Cu" signal "IN6")
		(34 "In16.Cu" signal "GND7")
		(2 "B.Cu" signal "BOTTOM")
		(9 "F.Adhes" user "F.Adhesive")
		(11 "B.Adhes" user "B.Adhesive")
		(13 "F.Paste" user "Package Geometry/Pastemask Top")
		(15 "B.Paste" user "Package Geometry/Pastemask Bottom")
		(5 "F.SilkS" user "Ref Des/Silkscreen Top")
		(7 "B.SilkS" user "Ref Des/Silkscreen Bottom")
		(1 "F.Mask" user "Board Geometry/Soldermask Top")
		(3 "B.Mask" user "Board Geometry/Soldermask Bottom")
		(17 "Dwgs.User" user "User.Drawings")
		(19 "Cmts.User" user "User.Comments")
		(21 "Eco1.User" user "User.Eco1")
		(23 "Eco2.User" user "User.Eco2")
		(25 "Edge.Cuts" user "Board Geometry/Outline")
		(27 "Margin" user)
		(31 "F.CrtYd" user "Package Geometry/Place Bound Top")
		(29 "B.CrtYd" user "Package Geometry/Place Bound Bottom")
		(35 "F.Fab" user "Ref Des/Assembly Top")
		(33 "B.Fab" user "Ref Des/Assembly Bottom")
	)
	(footprint ""
		(layer "B.Cu")
		(at 213.801198 -220.322902)
		(property "Reference" "R4888"
			(at 0 0 0)
			(layer "B.SilkS")
			(hide yes)
			(effects
				(font
					(size 1.27 1.27)
				)
				(justify mirror)
			)
		)
		(property "Value" ""
			(at 0 0 0)
			(layer "B.Fab")
			(effects
				(font
					(size 1.27 1.27)
				)
				(justify mirror)
			)
		)
		(duplicate_pad_numbers_are_jumpers no)
		(fp_line
			(start -0.7874 -0.4064)
			(end -0.7874 0.4064)
			(stroke
				(width 0.1524)
				(type default)
			)
			(layer "B.SilkS")
		)
		(fp_line
			(start -0.7874 0.4064)
			(end 0.7874 0.4064)
			(stroke
				(width 0.1524)
				(type default)
			)
			(layer "B.SilkS")
		)
		(fp_line
			(start 0.7874 -0.4064)
			(end -0.7874 -0.4064)
			(stroke
				(width 0.1524)
				(type default)
			)
			(layer "B.SilkS")
		)
		(fp_line
			(start 0.7874 0.4064)
			(end 0.7874 -0.4064)
			(stroke
				(width 0.1524)
				(type default)
			)
			(layer "B.SilkS")
		)
		(fp_line
			(start -0.67945 -0.3048)
			(end -0.67945 0.3048)
			(stroke
				(width 0.1)
				(type default)
			)
			(layer "B.Fab")
		)
		(fp_line
			(start -0.67945 0.3048)
			(end -0.120396 0.3048)
			(stroke
				(width 0.1)
				(type default)
			)
			(layer "B.Fab")
		)
		(fp_line
			(start -0.12065 -0.3048)
			(end -0.67945 -0.3048)
			(stroke
				(width 0.1)
				(type default)
			)
			(layer "B.Fab")
		)
		(fp_line
			(start -0.12065 -0.2794)
			(end -0.12065 -0.3048)
			(stroke
				(width 0.1)
				(type default)
			)
			(layer "B.Fab")
		)
		(fp_line
			(start -0.120396 0.2794)
			(end 0.12065 0.2794)
			(stroke
				(width 0.1)
				(type default)
			)
			(layer "B.Fab")
		)
		(fp_line
			(start -0.120396 0.3048)
			(end -0.120396 0.2794)
			(stroke
				(width 0.1)
				(type default)
			)
			(layer "B.Fab")
		)
		(fp_line
			(start 0.12065 -0.305054)
			(end 0.12065 -0.2794)
			(stroke
				(width 0.1)
				(type default)
			)
			(layer "B.Fab")
		)
		(fp_line
			(start 0.12065 -0.2794)
			(end -0.12065 -0.2794)
			(stroke
				(width 0.1)
				(type default)
			)
			(layer "B.Fab")
		)
		(fp_line
			(start 0.12065 0.2794)
			(end 0.12065 0.3048)
			(stroke
				(width 0.1)
				(type default)
			)
			(layer "B.Fab")
		)
		(fp_line
			(start 0.12065 0.3048)
			(end 0.67945 0.3048)
			(stroke
				(width 0.1)
				(type default)
			)
			(layer "B.Fab")
		)
		(fp_line
			(start 0.67945 -0.305054)
			(end 0.12065 -0.305054)
			(stroke
				(width 0.1)
				(type default)
			)
			(layer "B.Fab")
		)
		(fp_line
			(start 0.67945 0.3048)
			(end 0.67945 -0.305054)
			(stroke
				(width 0.1)
				(type default)
			)
			(layer "B.Fab")
		)
		(pad "1" smd circle
			(at 0.40005 0 180)
			(size 0 0)
			(layers "B.Cu" "B.Mask" "B.Paste")
			(net "SMB_PEX_R_SDA")
		)
		(pad "2" smd circle
			(at -0.40005 0 180)
			(size 0 0)
			(layers "B.Cu" "B.Mask" "B.Paste")
			(net "P3V3_AUX")
		)
	)
	(footprint ""
		(layer "B.Cu")
		(at 101.223318 -389.9408 180)
		(property "Reference" "C3630"
			(at 0 0 0)
			(layer "B.SilkS")
			(hide yes)
			(effects
				(font
					(size 1.27 1.27)
				)
				(justify mirror)
			)
		)
		(property "Value" ""
			(at 0 0 0)
			(layer "B.Fab")
			(effects
				(font
					(size 1.27 1.27)
				)
				(justify mirror)
			)
		)
		(duplicate_pad_numbers_are_jumpers no)
		(fp_line
			(start 0.7874 0.4064)
			(end 0.7874 -0.4064)
			(stroke
				(width 0.1524)
				(type default)
			)
			(layer "B.SilkS")
		)
		(fp_line
			(start 0.7874 -0.4064)
			(end -0.7874 -0.4064)
			(stroke
				(width 0.1524)
				(type default)
			)
			(layer "B.SilkS")
		)
		(fp_line
			(start -0.7874 0.4064)
			(end 0.7874 0.4064)
			(stroke
				(width 0.1524)
				(type default)
			)
			(layer "B.SilkS")
		)
		(fp_line
			(start -0.7874 -0.4064)
			(end -0.7874 0.4064)
			(stroke
				(width 0.1524)
				(type default)
			)
			(layer "B.SilkS")
		)
		(fp_line
			(start 0.67945 0.3048)
			(end 0.67945 -0.305054)
			(stroke
				(width 0.1)
				(type default)
			)
			(layer "B.Fab")
		)
		(fp_line
			(start 0.67945 -0.305054)
			(end 0.12065 -0.305054)
			(stroke
				(width 0.1)
				(type default)
			)
			(layer "B.Fab")
		)
		(fp_line
			(start 0.12065 0.3048)
			(end 0.67945 0.3048)
			(stroke
				(width 0.1)
				(type default)
			)
			(layer "B.Fab")
		)
		(fp_line
			(start 0.12065 0.2794)
			(end 0.12065 0.3048)
			(stroke
				(width 0.1)
				(type default)
			)
			(layer "B.Fab")
		)
		(fp_line
			(start 0.12065 -0.2794)
			(end -0.12065 -0.2794)
			(stroke
				(width 0.1)
				(type default)
			)
			(layer "B.Fab")
		)
		(fp_line
			(start 0.12065 -0.305054)
			(end 0.12065 -0.2794)
			(stroke
				(width 0.1)
				(type default)
			)
			(layer "B.Fab")
		)
		(fp_line
			(start -0.120396 0.3048)
			(end -0.120396 0.2794)
			(stroke
				(width 0.1)
				(type default)
			)
			(layer "B.Fab")
		)
		(fp_line
			(start -0.120396 0.2794)
			(end 0.12065 0.2794)
			(stroke
				(width 0.1)
				(type default)
			)
			(layer "B.Fab")
		)
		(fp_line
			(start -0.12065 -0.2794)
			(end -0.12065 -0.3048)
			(stroke
				(width 0.1)
				(type default)
			)
			(layer "B.Fab")
		)
		(fp_line
			(start -0.12065 -0.3048)
			(end -0.67945 -0.3048)
			(stroke
				(width 0.1)
				(type default)
			)
			(layer "B.Fab")
		)
		(fp_line
			(start -0.67945 0.3048)
			(end -0.120396 0.3048)
			(stroke
				(width 0.1)
				(type default)
			)
			(layer "B.Fab")
		)
		(fp_line
			(start -0.67945 -0.3048)
			(end -0.67945 0.3048)
			(stroke
				(width 0.1)
				(type default)
			)
			(layer "B.Fab")
		)
		(pad "1" smd circle
			(at 0.40005 0)
			(size 0 0)
			(layers "B.Cu" "B.Mask" "B.Paste")
			(net "P3V3_BIC_USB_HUB")
		)
		(pad "2" smd circle
			(at -0.40005 0)
			(size 0 0)
			(layers "B.Cu" "B.Mask" "B.Paste")
			(net "GND")
		)
	)
	(footprint ""
		(layer "B.Cu")
		(at 385.943602 -237.29696)
		(property "Reference" "L4"
			(at 0 0 0)
			(layer "B.SilkS")
			(hide yes)
			(effects
				(font
					(size 1.27 1.27)
				)
				(justify mirror)
			)
		)
		(property "Value" ""
			(at 0 0 0)
			(layer "B.Fab")
			(effects
				(font
					(size 1.27 1.27)
				)
				(justify mirror)
			)
		)
		(duplicate_pad_numbers_are_jumpers no)
		(fp_line
			(start -1.27 0.5842)
			(end -1.27 -0.5842)
			(stroke
				(width 0.1524)
				(type default)
			)
			(layer "B.SilkS")
		)
		(fp_line
			(start -1.27 0.5842)
			(end 1.27 0.5842)
			(stroke
				(width 0.1524)
				(type default)
			)
			(layer "B.SilkS")
		)
		(fp_line
			(start 1.27 -0.5842)
			(end -1.27 -0.5842)
			(stroke
				(width 0.1524)
				(type default)
			)
			(layer "B.SilkS")
		)
		(fp_line
			(start 1.27 -0.5588)
			(end 1.27 -0.5842)
			(stroke
				(width 0.1524)
				(type default)
			)
			(layer "B.SilkS")
		)
		(fp_line
			(start 1.27 0.5842)
			(end 1.27 -0.5842)
			(stroke
				(width 0.1524)
				(type default)
			)
			(layer "B.SilkS")
		)
		(fp_line
			(start -1.1938 -0.406654)
			(end -1.1938 0.4064)
			(stroke
				(width 0.1)
				(type default)
			)
			(layer "B.Fab")
		)
		(fp_line
			(start -1.1938 0.4064)
			(end -0.9144 0.4064)
			(stroke
				(width 0.1)
				(type default)
			)
			(layer "B.Fab")
		)
		(fp_line
			(start -0.9144 -0.508)
			(end -0.9144 -0.406654)
			(stroke
				(width 0.1)
				(type default)
			)
			(layer "B.Fab")
		)
		(fp_line
			(start -0.9144 -0.406654)
			(end -1.1938 -0.406654)
			(stroke
				(width 0.1)
				(type default)
			)
			(layer "B.Fab")
		)
		(fp_line
			(start -0.9144 0.4064)
			(end -0.9144 0.508)
			(stroke
				(width 0.1)
				(type default)
			)
			(layer "B.Fab")
		)
		(fp_line
			(start -0.9144 0.508)
			(end 0.9144 0.508)
			(stroke
				(width 0.1)
				(type default)
			)
			(layer "B.Fab")
		)
		(fp_line
			(start 0.9144 -0.508)
			(end -0.9144 -0.508)
			(stroke
				(width 0.1)
				(type default)
			)
			(layer "B.Fab")
		)
		(fp_line
			(start 0.9144 -0.406654)
			(end 0.9144 -0.508)
			(stroke
				(width 0.1)
				(type default)
			)
			(layer "B.Fab")
		)
		(fp_line
			(start 0.9144 0.406654)
			(end 1.194308 0.406654)
			(stroke
				(width 0.1)
				(type default)
			)
			(layer "B.Fab")
		)
		(fp_line
			(start 0.9144 0.508)
			(end 0.9144 0.406654)
			(stroke
				(width 0.1)
				(type default)
			)
			(layer "B.Fab")
		)
		(fp_line
			(start 1.194308 -0.406654)
			(end 0.9144 -0.406654)
			(stroke
				(width 0.1)
				(type default)
			)
			(layer "B.Fab")
		)
		(fp_line
			(start 1.194308 0.406654)
			(end 1.194308 -0.406654)
			(stroke
				(width 0.1)
				(type default)
			)
			(layer "B.Fab")
		)
		(pad "1" smd rect
			(at 0.7366 0 270)
			(size 0.7112 0.8128)
			(layers "B.Cu" "B.Mask" "B.Paste")
			(net "P3V3_AUX")
		)
		(pad "2" smd rect
			(at -0.7366 0 270)
			(size 0.7112 0.8128)
			(layers "B.Cu" "B.Mask" "B.Paste")
			(net "P3V3_SDB_VPLL")
		)
	)
	(footprint ""
		(layer "B.Cu")
		(at 272.373598 -295.79824 180)
		(property "Reference" "R3475"
			(at 0 0 0)
			(layer "B.SilkS")
			(hide yes)
			(effects
				(font
					(size 1.27 1.27)
				)
				(justify mirror)
			)
		)
		(property "Value" ""
			(at 0 0 0)
			(layer "B.Fab")
			(effects
				(font
					(size 1.27 1.27)
				)
				(justify mirror)
			)
		)
		(duplicate_pad_numbers_are_jumpers no)
		(fp_line
			(start 0.7874 0.4064)
			(end 0.7874 -0.4064)
			(stroke
				(width 0.1524)
				(type default)
			)
			(layer "B.SilkS")
		)
		(fp_line
			(start 0.7874 -0.4064)
			(end -0.7874 -0.4064)
			(stroke
				(width 0.1524)
				(type default)
			)
			(layer "B.SilkS")
		)
		(fp_line
			(start -0.7874 0.4064)
			(end 0.7874 0.4064)
			(stroke
				(width 0.1524)
				(type default)
			)
			(layer "B.SilkS")
		)
		(fp_line
			(start -0.7874 -0.4064)
			(end -0.7874 0.4064)
			(stroke
				(width 0.1524)
				(type default)
			)
			(layer "B.SilkS")
		)
		(fp_line
			(start 0.67945 0.3048)
			(end 0.67945 -0.305054)
			(stroke
				(width 0.1)
				(type default)
			)
			(layer "B.Fab")
		)
		(fp_line
			(start 0.67945 -0.305054)
			(end 0.12065 -0.305054)
			(stroke
				(width 0.1)
				(type default)
			)
			(layer "B.Fab")
		)
		(fp_line
			(start 0.12065 0.3048)
			(end 0.67945 0.3048)
			(stroke
				(width 0.1)
				(type default)
			)
			(layer "B.Fab")
		)
		(fp_line
			(start 0.12065 0.2794)
			(end 0.12065 0.3048)
			(stroke
				(width 0.1)
				(type default)
			)
			(layer "B.Fab")
		)
		(fp_line
			(start 0.12065 -0.2794)
			(end -0.12065 -0.2794)
			(stroke
				(width 0.1)
				(type default)
			)
			(layer "B.Fab")
		)
		(fp_line
			(start 0.12065 -0.305054)
			(end 0.12065 -0.2794)
			(stroke
				(width 0.1)
				(type default)
			)
			(layer "B.Fab")
		)
		(fp_line
			(start -0.120396 0.3048)
			(end -0.120396 0.2794)
			(stroke
				(width 0.1)
				(type default)
			)
			(layer "B.Fab")
		)
		(fp_line
			(start -0.120396 0.2794)
			(end 0.12065 0.2794)
			(stroke
				(width 0.1)
				(type default)
			)
			(layer "B.Fab")
		)
		(fp_line
			(start -0.12065 -0.2794)
			(end -0.12065 -0.3048)
			(stroke
				(width 0.1)
				(type default)
			)
			(layer "B.Fab")
		)
		(fp_line
			(start -0.12065 -0.3048)
			(end -0.67945 -0.3048)
			(stroke
				(width 0.1)
				(type default)
			)
			(layer "B.Fab")
		)
		(fp_line
			(start -0.67945 0.3048)
			(end -0.120396 0.3048)
			(stroke
				(width 0.1)
				(type default)
			)
			(layer "B.Fab")
		)
		(fp_line
			(start -0.67945 -0.3048)
			(end -0.67945 0.3048)
			(stroke
				(width 0.1)
				(type default)
			)
			(layer "B.Fab")
		)
		(pad "1" smd circle
			(at 0.40005 0)
			(size 0 0)
			(layers "B.Cu" "B.Mask" "B.Paste")
			(net "SPI_PEX2_SDIO0_R")
		)
		(pad "2" smd circle
			(at -0.40005 0)
			(size 0 0)
			(layers "B.Cu" "B.Mask" "B.Paste")
			(net "SPI_PEX2_SDIO0")
		)
	)
	(footprint ""
		(layer "B.Cu")
		(at 340.339426 -85.597746)
		(property "Reference" "C2678"
			(at 0 0 0)
			(layer "B.SilkS")
			(hide yes)
			(effects
				(font
					(size 1.27 1.27)
				)
				(justify mirror)
			)
		)
		(property "Value" ""
			(at 0 0 0)
			(layer "B.Fab")
			(effects
				(font
					(size 1.27 1.27)
				)
				(justify mirror)
			)
		)
		(duplicate_pad_numbers_are_jumpers no)
		(fp_line
			(start -0.7874 -0.4064)
			(end -0.7874 0.4064)
			(stroke
				(width 0.1524)
				(type default)
			)
			(layer "B.SilkS")
		)
		(fp_line
			(start -0.7874 0.4064)
			(end 0.7874 0.4064)
			(stroke
				(width 0.1524)
				(type default)
			)
			(layer "B.SilkS")
		)
		(fp_line
			(start 0.7874 -0.4064)
			(end -0.7874 -0.4064)
			(stroke
				(width 0.1524)
				(type default)
			)
			(layer "B.SilkS")
		)
		(fp_line
			(start 0.7874 0.4064)
			(end 0.7874 -0.4064)
			(stroke
				(width 0.1524)
				(type default)
			)
			(layer "B.SilkS")
		)
		(fp_line
			(start -0.67945 -0.3048)
			(end -0.67945 0.3048)
			(stroke
				(width 0.1)
				(type default)
			)
			(layer "B.Fab")
		)
		(fp_line
			(start -0.67945 0.3048)
			(end -0.120396 0.3048)
			(stroke
				(width 0.1)
				(type default)
			)
			(layer "B.Fab")
		)
		(fp_line
			(start -0.12065 -0.3048)
			(end -0.67945 -0.3048)
			(stroke
				(width 0.1)
				(type default)
			)
			(layer "B.Fab")
		)
		(fp_line
			(start -0.12065 -0.2794)
			(end -0.12065 -0.3048)
			(stroke
				(width 0.1)
				(type default)
			)
			(layer "B.Fab")
		)
		(fp_line
			(start -0.120396 0.2794)
			(end 0.12065 0.2794)
			(stroke
				(width 0.1)
				(type default)
			)
			(layer "B.Fab")
		)
		(fp_line
			(start -0.120396 0.3048)
			(end -0.120396 0.2794)
			(stroke
				(width 0.1)
				(type default)
			)
			(layer "B.Fab")
		)
		(fp_line
			(start 0.12065 -0.305054)
			(end 0.12065 -0.2794)
			(stroke
				(width 0.1)
				(type default)
			)
			(layer "B.Fab")
		)
		(fp_line
			(start 0.12065 -0.2794)
			(end -0.12065 -0.2794)
			(stroke
				(width 0.1)
				(type default)
			)
			(layer "B.Fab")
		)
		(fp_line
			(start 0.12065 0.2794)
			(end 0.12065 0.3048)
			(stroke
				(width 0.1)
				(type default)
			)
			(layer "B.Fab")
		)
		(fp_line
			(start 0.12065 0.3048)
			(end 0.67945 0.3048)
			(stroke
				(width 0.1)
				(type default)
			)
			(layer "B.Fab")
		)
		(fp_line
			(start 0.67945 -0.305054)
			(end 0.12065 -0.305054)
			(stroke
				(width 0.1)
				(type default)
			)
			(layer "B.Fab")
		)
		(fp_line
			(start 0.67945 0.3048)
			(end 0.67945 -0.305054)
			(stroke
				(width 0.1)
				(type default)
			)
			(layer "B.Fab")
		)
		(pad "1" smd circle
			(at 0.40005 0 180)
			(size 0 0)
			(layers "B.Cu" "B.Mask" "B.Paste")
			(net "P3V3_VDD_9ZXL0851_8_15")
		)
		(pad "2" smd circle
			(at -0.40005 0 180)
			(size 0 0)
			(layers "B.Cu" "B.Mask" "B.Paste")
			(net "GND")
		)
	)
	(footprint ""
		(layer "B.Cu")
		(at 388.473696 -296.9514 180)
		(property "Reference" "R3493"
			(at 0 0 0)
			(layer "B.SilkS")
			(hide yes)
			(effects
				(font
					(size 1.27 1.27)
				)
				(justify mirror)
			)
		)
		(property "Value" ""
			(at 0 0 0)
			(layer "B.Fab")
			(effects
				(font
					(size 1.27 1.27)
				)
				(justify mirror)
			)
		)
		(duplicate_pad_numbers_are_jumpers no)
		(fp_line
			(start 0.7874 0.4064)
			(end 0.7874 -0.4064)
			(stroke
				(width 0.1524)
				(type default)
			)
			(layer "B.SilkS")
		)
		(fp_line
			(start 0.7874 -0.4064)
			(end -0.7874 -0.4064)
			(stroke
				(width 0.1524)
				(type default)
			)
			(layer "B.SilkS")
		)
		(fp_line
			(start -0.7874 0.4064)
			(end 0.7874 0.4064)
			(stroke
				(width 0.1524)
				(type default)
			)
			(layer "B.SilkS")
		)
		(fp_line
			(start -0.7874 -0.4064)
			(end -0.7874 0.4064)
			(stroke
				(width 0.1524)
				(type default)
			)
			(layer "B.SilkS")
		)
		(fp_line
			(start 0.67945 0.3048)
			(end 0.67945 -0.305054)
			(stroke
				(width 0.1)
				(type default)
			)
			(layer "B.Fab")
		)
		(fp_line
			(start 0.67945 -0.305054)
			(end 0.12065 -0.305054)
			(stroke
				(width 0.1)
				(type default)
			)
			(layer "B.Fab")
		)
		(fp_line
			(start 0.12065 0.3048)
			(end 0.67945 0.3048)
			(stroke
				(width 0.1)
				(type default)
			)
			(layer "B.Fab")
		)
		(fp_line
			(start 0.12065 0.2794)
			(end 0.12065 0.3048)
			(stroke
				(width 0.1)
				(type default)
			)
			(layer "B.Fab")
		)
		(fp_line
			(start 0.12065 -0.2794)
			(end -0.12065 -0.2794)
			(stroke
				(width 0.1)
				(type default)
			)
			(layer "B.Fab")
		)
		(fp_line
			(start 0.12065 -0.305054)
			(end 0.12065 -0.2794)
			(stroke
				(width 0.1)
				(type default)
			)
			(layer "B.Fab")
		)
		(fp_line
			(start -0.120396 0.3048)
			(end -0.120396 0.2794)
			(stroke
				(width 0.1)
				(type default)
			)
			(layer "B.Fab")
		)
		(fp_line
			(start -0.120396 0.2794)
			(end 0.12065 0.2794)
			(stroke
				(width 0.1)
				(type default)
			)
			(layer "B.Fab")
		)
		(fp_line
			(start -0.12065 -0.2794)
			(end -0.12065 -0.3048)
			(stroke
				(width 0.1)
				(type default)
			)
			(layer "B.Fab")
		)
		(fp_line
			(start -0.12065 -0.3048)
			(end -0.67945 -0.3048)
			(stroke
				(width 0.1)
				(type default)
			)
			(layer "B.Fab")
		)
		(fp_line
			(start -0.67945 0.3048)
			(end -0.120396 0.3048)
			(stroke
				(width 0.1)
				(type default)
			)
			(layer "B.Fab")
		)
		(fp_line
			(start -0.67945 -0.3048)
			(end -0.67945 0.3048)
			(stroke
				(width 0.1)
				(type default)
			)
			(layer "B.Fab")
		)
		(pad "1" smd circle
			(at 0.40005 0)
			(size 0 0)
			(layers "B.Cu" "B.Mask" "B.Paste")
			(net "SPI_PEX3_SDIO1_R")
		)
		(pad "2" smd circle
			(at -0.40005 0)
			(size 0 0)
			(layers "B.Cu" "B.Mask" "B.Paste")
			(net "SPI_PEX3_SDIO1")
		)
	)
)
